(kicad_pcb
	(version 20260206)
	(generator "pcbnew")
	(generator_version "10.0")
	(general
		(thickness 1.6)
		(legacy_teardrops no)
	)
	(paper "A4")
	(title_block
		(title "9052_F0T_PDB_Converter_Brick_F_V03_1208_1600_OCP.brd")
		(comment 1 "Grand Teton / footprints 191-197 of 578")
	)
	(layers
		(0 "F.Cu" signal "TOP")
		(4 "In1.Cu" signal "GND")
		(6 "In2.Cu" signal "IN1")
		(8 "In3.Cu" signal "GND1")
		(10 "In4.Cu" signal "VCC")
		(12 "In5.Cu" signal "VCC1")
		(14 "In6.Cu" signal "GND2")
		(16 "In7.Cu" signal "IN2")
		(18 "In8.Cu" signal "GND3")
		(2 "B.Cu" signal "BOTTOM")
		(9 "F.Adhes" user "F.Adhesive")
		(11 "B.Adhes" user "B.Adhesive")
		(13 "F.Paste" user "Package Geometry/Pastemask Top")
		(15 "B.Paste" user "Package Geometry/Pastemask Bottom")
		(5 "F.SilkS" user "Ref Des/Silkscreen Top")
		(7 "B.SilkS" user "Ref Des/Silkscreen Bottom")
		(1 "F.Mask" user "Board Geometry/Soldermask Top")
		(3 "B.Mask" user "Board Geometry/Soldermask Bottom")
		(17 "Dwgs.User" user "User.Drawings")
		(19 "Cmts.User" user "User.Comments")
		(21 "Eco1.User" user "User.Eco1")
		(23 "Eco2.User" user "User.Eco2")
		(25 "Edge.Cuts" user "Board Geometry/Outline")
		(27 "Margin" user)
		(31 "F.CrtYd" user "Package Geometry/Place Bound Top")
		(29 "B.CrtYd" user "Package Geometry/Place Bound Bottom")
		(35 "F.Fab" user "Ref Des/Assembly Top")
		(33 "B.Fab" user "Ref Des/Assembly Bottom")
	)
	(footprint ""
		(layer "F.Cu")
		(at 279.908 -44.069)
		(property "Reference" "PR6934"
			(at 0 0 0)
			(layer "F.SilkS")
			(hide yes)
			(effects
				(font
					(size 1.27 1.27)
				)
			)
		)
		(property "Value" ""
			(at 0 0 0)
			(layer "F.Fab")
			(effects
				(font
					(size 1.27 1.27)
				)
			)
		)
		(duplicate_pad_numbers_are_jumpers no)
		(fp_line
			(start -0.7874 -0.4064)
			(end 0.7874 -0.4064)
			(stroke
				(width 0.1524)
				(type default)
			)
			(layer "F.SilkS")
		)
		(fp_line
			(start -0.7874 0.4064)
			(end -0.7874 -0.4064)
			(stroke
				(width 0.1524)
				(type default)
			)
			(layer "F.SilkS")
		)
		(fp_line
			(start 0.7874 -0.4064)
			(end 0.7874 0.4064)
			(stroke
				(width 0.1524)
				(type default)
			)
			(layer "F.SilkS")
		)
		(fp_line
			(start 0.7874 0.4064)
			(end -0.7874 0.4064)
			(stroke
				(width 0.1524)
				(type default)
			)
			(layer "F.SilkS")
		)
		(fp_line
			(start -0.67945 -0.305054)
			(end -0.12065 -0.305054)
			(stroke
				(width 0.1)
				(type default)
			)
			(layer "F.Fab")
		)
		(fp_line
			(start -0.67945 0.3048)
			(end -0.67945 -0.305054)
			(stroke
				(width 0.1)
				(type default)
			)
			(layer "F.Fab")
		)
		(fp_line
			(start -0.12065 -0.305054)
			(end -0.12065 -0.2794)
			(stroke
				(width 0.1)
				(type default)
			)
			(layer "F.Fab")
		)
		(fp_line
			(start -0.12065 -0.2794)
			(end 0.12065 -0.2794)
			(stroke
				(width 0.1)
				(type default)
			)
			(layer "F.Fab")
		)
		(fp_line
			(start -0.12065 0.2794)
			(end -0.12065 0.3048)
			(stroke
				(width 0.1)
				(type default)
			)
			(layer "F.Fab")
		)
		(fp_line
			(start -0.12065 0.3048)
			(end -0.67945 0.3048)
			(stroke
				(width 0.1)
				(type default)
			)
			(layer "F.Fab")
		)
		(fp_line
			(start 0.120396 0.2794)
			(end -0.12065 0.2794)
			(stroke
				(width 0.1)
				(type default)
			)
			(layer "F.Fab")
		)
		(fp_line
			(start 0.120396 0.3048)
			(end 0.120396 0.2794)
			(stroke
				(width 0.1)
				(type default)
			)
			(layer "F.Fab")
		)
		(fp_line
			(start 0.12065 -0.3048)
			(end 0.67945 -0.3048)
			(stroke
				(width 0.1)
				(type default)
			)
			(layer "F.Fab")
		)
		(fp_line
			(start 0.12065 -0.2794)
			(end 0.12065 -0.3048)
			(stroke
				(width 0.1)
				(type default)
			)
			(layer "F.Fab")
		)
		(fp_line
			(start 0.67945 -0.3048)
			(end 0.67945 0.3048)
			(stroke
				(width 0.1)
				(type default)
			)
			(layer "F.Fab")
		)
		(fp_line
			(start 0.67945 0.3048)
			(end 0.120396 0.3048)
			(stroke
				(width 0.1)
				(type default)
			)
			(layer "F.Fab")
		)
		(pad "1" smd circle
			(at -0.40005 0)
			(size 0 0)
			(layers "F.Cu" "F.Mask" "F.Paste")
			(net "P52V_HS1_ISTART")
		)
		(pad "2" smd circle
			(at 0.40005 0)
			(size 0 0)
			(layers "F.Cu" "F.Mask" "F.Paste")
			(net "P52V_HS1_VCAP")
		)
	)
	(footprint ""
		(layer "F.Cu")
		(at 209.931 -93.6244 180)
		(property "Reference" "R57"
			(at 0 0 180)
			(layer "F.SilkS")
			(hide yes)
			(effects
				(font
					(size 1.27 1.27)
				)
			)
		)
		(property "Value" ""
			(at 0 0 180)
			(layer "F.Fab")
			(effects
				(font
					(size 1.27 1.27)
				)
			)
		)
		(duplicate_pad_numbers_are_jumpers no)
		(fp_line
			(start 2.234946 0.9271)
			(end -2.234946 0.9271)
			(stroke
				(width 0.1524)
				(type default)
			)
			(layer "F.SilkS")
		)
		(fp_line
			(start 2.234946 -0.9271)
			(end 2.234946 0.9271)
			(stroke
				(width 0.1524)
				(type default)
			)
			(layer "F.SilkS")
		)
		(fp_line
			(start -2.234946 0.9271)
			(end -2.234946 -0.9271)
			(stroke
				(width 0.1524)
				(type default)
			)
			(layer "F.SilkS")
		)
		(fp_line
			(start -2.234946 -0.9271)
			(end 2.234946 -0.9271)
			(stroke
				(width 0.1524)
				(type default)
			)
			(layer "F.SilkS")
		)
		(fp_line
			(start 1.575054 0.824992)
			(end 1.575054 -0.824992)
			(stroke
				(width 0.1)
				(type default)
			)
			(layer "F.Fab")
		)
		(fp_line
			(start 1.575054 -0.824992)
			(end -1.575054 -0.824992)
			(stroke
				(width 0.1)
				(type default)
			)
			(layer "F.Fab")
		)
		(fp_line
			(start -1.575054 0.824992)
			(end 1.575054 0.824992)
			(stroke
				(width 0.1)
				(type default)
			)
			(layer "F.Fab")
		)
		(fp_line
			(start -1.575054 -0.824992)
			(end -1.575054 0.824992)
			(stroke
				(width 0.1)
				(type default)
			)
			(layer "F.Fab")
		)
		(pad "1" smd rect
			(at -1.599946 0 180)
			(size 1.016 1.6002)
			(layers "F.Cu" "F.Mask" "F.Paste")
			(net "LED_D1_R1")
		)
		(pad "2" smd rect
			(at 1.599946 0 180)
			(size 1.016 1.6002)
			(layers "F.Cu" "F.Mask" "F.Paste")
			(net "LED_D1_R2")
		)
	)
	(footprint ""
		(layer "F.Cu")
		(at 186.431174 -136.906 90)
		(property "Reference" "PC113"
			(at 6.06933 0.639826 0)
			(unlocked yes)
			(layer "F.SilkS")
			(effects
				(font
					(size 0.7874 0.5842)
					(thickness 0.1524)
				)
				(justify left)
			)
		)
		(property "Value" ""
			(at 0 0 90)
			(layer "F.Fab")
			(effects
				(font
					(size 1.27 1.27)
				)
			)
		)
		(duplicate_pad_numbers_are_jumpers no)
		(fp_line
			(start 5.2578 2.499868)
			(end -5.2578 2.499868)
			(stroke
				(width 0.1524)
				(type default)
			)
			(layer "F.SilkS")
		)
		(fp_circle
			(center 0 2.500122)
			(end 0 7.758176)
			(stroke
				(width 0.1524)
				(type default)
			)
			(fill no)
			(layer "F.SilkS")
		)
		(fp_poly
			(pts
				(arc
					(start 5.2578 2.499868)
					(mid 0 7.757922)
					(end -5.2578 2.499868)
				)
			)
			(stroke
				(width 0)
				(type default)
			)
			(fill yes)
			(layer "F.SilkS")
		)
		(fp_circle
			(center 0 2.500122)
			(end 0 7.758176)
			(stroke
				(width 0.1)
				(type default)
			)
			(fill no)
			(layer "F.Fab")
		)
		(pad "1" thru_hole rect
			(at 0 0)
			(size 1.5748 1.5748)
			(drill 1.0668)
			(layers "*.Cu" "*.Mask")
			(remove_unused_layers no)
			(net "P52V_HS_FILTER")
			(clearance 0)
			(padstack
				(mode front_inner_back)
				(layer "Inner"
					(shape circle)
					(size 1.5748 1.5748)
					(clearance 0)
				)
				(layer "B.Cu"
					(shape rect)
					(size 1.5748 1.5748)
					(clearance 0)
				)
			)
		)
		(pad "2" thru_hole circle
			(at 0 4.99999)
			(size 1.5748 1.5748)
			(drill 1.0668)
			(layers "*.Cu" "*.Mask")
			(remove_unused_layers no)
			(net "GND")
			(clearance 0)
		)
	)
	(footprint ""
		(layer "F.Cu")
		(at 241.808 -95.504 -90)
		(property "Reference" "C45"
			(at 0 0 270)
			(layer "F.SilkS")
			(hide yes)
			(effects
				(font
					(size 1.27 1.27)
				)
			)
		)
		(property "Value" ""
			(at 0 0 270)
			(layer "F.Fab")
			(effects
				(font
					(size 1.27 1.27)
				)
			)
		)
		(duplicate_pad_numbers_are_jumpers no)
		(fp_line
			(start -2.2098 0.9398)
			(end -2.2098 -0.9398)
			(stroke
				(width 0.1524)
				(type default)
			)
			(layer "F.SilkS")
		)
		(fp_line
			(start 2.2098 0.9398)
			(end -2.2098 0.9398)
			(stroke
				(width 0.1524)
				(type default)
			)
			(layer "F.SilkS")
		)
		(fp_line
			(start -2.2098 -0.9398)
			(end 2.2098 -0.9398)
			(stroke
				(width 0.1524)
				(type default)
			)
			(layer "F.SilkS")
		)
		(fp_line
			(start 2.2098 -0.9398)
			(end 2.2098 0.9398)
			(stroke
				(width 0.1524)
				(type default)
			)
			(layer "F.SilkS")
		)
		(fp_line
			(start -1.700022 0.899922)
			(end -1.700022 -0.899922)
			(stroke
				(width 0.1)
				(type default)
			)
			(layer "F.Fab")
		)
		(fp_line
			(start 1.700022 0.899922)
			(end -1.700022 0.899922)
			(stroke
				(width 0.1)
				(type default)
			)
			(layer "F.Fab")
		)
		(fp_line
			(start -1.700022 -0.899922)
			(end 1.700022 -0.899922)
			(stroke
				(width 0.1)
				(type default)
			)
			(layer "F.Fab")
		)
		(fp_line
			(start 1.700022 -0.899922)
			(end 1.700022 0.899922)
			(stroke
				(width 0.1)
				(type default)
			)
			(layer "F.Fab")
		)
		(pad "1" smd rect
			(at -1.4732 0 90)
			(size 1.1684 1.5748)
			(layers "F.Cu" "F.Mask" "F.Paste")
			(net "P52V_HS")
		)
		(pad "2" smd rect
			(at 1.4732 0 90)
			(size 1.1684 1.5748)
			(layers "F.Cu" "F.Mask" "F.Paste")
			(net "GND")
		)
	)
	(footprint ""
		(layer "F.Cu")
		(at 222.88754 -141.88948)
		(property "Reference" "H23"
			(at -1.143 -3.65633 0)
			(unlocked yes)
			(layer "F.SilkS")
			(effects
				(font
					(size 0.7874 0.5842)
					(thickness 0.1524)
				)
				(justify left)
			)
		)
		(property "Value" ""
			(at 0 0 0)
			(layer "F.Fab")
			(effects
				(font
					(size 1.27 1.27)
				)
			)
		)
		(duplicate_pad_numbers_are_jumpers no)
		(fp_circle
			(center 0 0)
			(end 2.4003 0)
			(stroke
				(width 0.1524)
				(type default)
			)
			(fill no)
			(layer "F.SilkS")
		)
		(fp_arc
			(start 5.098288 -4.177538)
			(mid 6.206839 -2.21816)
			(end 6.5913 0)
			(stroke
				(width 0.1524)
				(type default)
			)
			(layer "B.SilkS")
		)
		(fp_arc
			(start 6.5913 0)
			(mid -2.179183 6.220643)
			(end -5.150358 -4.113276)
			(stroke
				(width 0.1524)
				(type default)
			)
			(layer "B.SilkS")
		)
		(fp_circle
			(center 0 0)
			(end 6.5913 0)
			(stroke
				(width 0.1)
				(type default)
			)
			(fill no)
			(layer "B.Fab")
		)
		(fp_circle
			(center 0 0)
			(end 2.4003 0)
			(stroke
				(width 0.1)
				(type default)
			)
			(fill no)
			(layer "F.Fab")
		)
		(pad "" np_thru_hole circle
			(at 0 0)
			(size 3.175 3.175)
			(drill 3.175)
			(layers "*.Cu" "*.Mask")
			(clearance 0.381)
			(thermal_gap 0.381)
		)
		(zone
			(layers "F.Cu" "B.Cu" "In1.Cu" "In2.Cu" "In3.Cu" "In4.Cu" "In5.Cu" "In6.Cu"
				"In7.Cu" "In8.Cu"
			)
			(hatch none 0.5)
			(connect_pads
				(clearance 0)
			)
			(min_thickness 0.25)
			(keepout
				(tracks not_allowed)
				(vias allowed)
				(pads allowed)
				(copperpour not_allowed)
				(footprints allowed)
			)
			(placement
				(enabled no)
				(sheetname "")
			)
			(fill
				(thermal_gap 0.5)
				(thermal_bridge_width 0.5)
				(island_removal_mode 0)
			)
			(polygon
				(pts
					(arc
						(start 224.98304 -141.88948)
						(mid 220.79204 -141.88948)
						(end 224.98304 -141.88948)
					)
				)
			)
		)
	)
	(footprint ""
		(layer "F.Cu")
		(at 264.668 -32.131 180)
		(property "Reference" "PC83"
			(at 0 0 180)
			(layer "F.SilkS")
			(hide yes)
			(effects
				(font
					(size 1.27 1.27)
				)
			)
		)
		(property "Value" ""
			(at 0 0 180)
			(layer "F.Fab")
			(effects
				(font
					(size 1.27 1.27)
				)
			)
		)
		(duplicate_pad_numbers_are_jumpers no)
		(fp_line
			(start 1.2954 0.5842)
			(end -1.2954 0.5842)
			(stroke
				(width 0.1524)
				(type default)
			)
			(layer "F.SilkS")
		)
		(fp_line
			(start 1.2954 -0.5842)
			(end 1.2954 0.5842)
			(stroke
				(width 0.1524)
				(type default)
			)
			(layer "F.SilkS")
		)
		(fp_line
			(start -1.2954 0.5842)
			(end -1.2954 -0.5842)
			(stroke
				(width 0.1524)
				(type default)
			)
			(layer "F.SilkS")
		)
		(fp_line
			(start -1.2954 -0.5842)
			(end 1.2954 -0.5842)
			(stroke
				(width 0.1524)
				(type default)
			)
			(layer "F.SilkS")
		)
		(fp_line
			(start 1.1938 0.4064)
			(end 0.8636 0.4064)
			(stroke
				(width 0.1)
				(type default)
			)
			(layer "F.Fab")
		)
		(fp_line
			(start 1.1938 -0.4064)
			(end 1.1938 0.4064)
			(stroke
				(width 0.1)
				(type default)
			)
			(layer "F.Fab")
		)
		(fp_line
			(start 0.8636 0.4572)
			(end -0.8636 0.4572)
			(stroke
				(width 0.1)
				(type default)
			)
			(layer "F.Fab")
		)
		(fp_line
			(start 0.8636 0.4064)
			(end 0.8636 0.4572)
			(stroke
				(width 0.1)
				(type default)
			)
			(layer "F.Fab")
		)
		(fp_line
			(start 0.8636 -0.4064)
			(end 1.1938 -0.4064)
			(stroke
				(width 0.1)
				(type default)
			)
			(layer "F.Fab")
		)
		(fp_line
			(start 0.8636 -0.4572)
			(end 0.8636 -0.4064)
			(stroke
				(width 0.1)
				(type default)
			)
			(layer "F.Fab")
		)
		(fp_line
			(start -0.8636 0.4572)
			(end -0.8636 0.4064)
			(stroke
				(width 0.1)
				(type default)
			)
			(layer "F.Fab")
		)
		(fp_line
			(start -0.8636 0.4064)
			(end -1.1938 0.4064)
			(stroke
				(width 0.1)
				(type default)
			)
			(layer "F.Fab")
		)
		(fp_line
			(start -0.8636 -0.4064)
			(end -0.8636 -0.4572)
			(stroke
				(width 0.1)
				(type default)
			)
			(layer "F.Fab")
		)
		(fp_line
			(start -0.8636 -0.4572)
			(end 0.8636 -0.4572)
			(stroke
				(width 0.1)
				(type default)
			)
			(layer "F.Fab")
		)
		(fp_line
			(start -1.1938 0.4064)
			(end -1.1938 -0.4064)
			(stroke
				(width 0.1)
				(type default)
			)
			(layer "F.Fab")
		)
		(fp_line
			(start -1.1938 -0.4064)
			(end -0.8636 -0.4064)
			(stroke
				(width 0.1)
				(type default)
			)
			(layer "F.Fab")
		)
		(pad "1" smd rect
			(at -0.7366 0 90)
			(size 0.7112 0.8128)
			(layers "F.Cu" "F.Mask" "F.Paste")
			(net "HS1_TMR2")
		)
		(pad "2" smd rect
			(at 0.7366 0 90)
			(size 0.7112 0.8128)
			(layers "F.Cu" "F.Mask" "F.Paste")
			(net "GND_FIELD_SIGNAL")
		)
	)
	(footprint ""
		(layer "F.Cu")
		(at 285.623 -35.168078 180)
		(property "Reference" "R149"
			(at 0 0 180)
			(layer "F.SilkS")
			(hide yes)
			(effects
				(font
					(size 1.27 1.27)
				)
			)
		)
		(property "Value" ""
			(at 0 0 180)
			(layer "F.Fab")
			(effects
				(font
					(size 1.27 1.27)
				)
			)
		)
		(duplicate_pad_numbers_are_jumpers no)
		(fp_line
			(start 0.7874 0.4064)
			(end -0.7874 0.4064)
			(stroke
				(width 0.1524)
				(type default)
			)
			(layer "F.SilkS")
		)
		(fp_line
			(start 0.7874 -0.4064)
			(end 0.7874 0.4064)
			(stroke
				(width 0.1524)
				(type default)
			)
			(layer "F.SilkS")
		)
		(fp_line
			(start -0.7874 0.4064)
			(end -0.7874 -0.4064)
			(stroke
				(width 0.1524)
				(type default)
			)
			(layer "F.SilkS")
		)
		(fp_line
			(start -0.7874 -0.4064)
			(end 0.7874 -0.4064)
			(stroke
				(width 0.1524)
				(type default)
			)
			(layer "F.SilkS")
		)
		(fp_line
			(start 0.67945 0.3048)
			(end 0.120396 0.3048)
			(stroke
				(width 0.1)
				(type default)
			)
			(layer "F.Fab")
		)
		(fp_line
			(start 0.67945 -0.3048)
			(end 0.67945 0.3048)
			(stroke
				(width 0.1)
				(type default)
			)
			(layer "F.Fab")
		)
		(fp_line
			(start 0.12065 -0.2794)
			(end 0.12065 -0.3048)
			(stroke
				(width 0.1)
				(type default)
			)
			(layer "F.Fab")
		)
		(fp_line
			(start 0.12065 -0.3048)
			(end 0.67945 -0.3048)
			(stroke
				(width 0.1)
				(type default)
			)
			(layer "F.Fab")
		)
		(fp_line
			(start 0.120396 0.3048)
			(end 0.120396 0.2794)
			(stroke
				(width 0.1)
				(type default)
			)
			(layer "F.Fab")
		)
		(fp_line
			(start 0.120396 0.2794)
			(end -0.12065 0.2794)
			(stroke
				(width 0.1)
				(type default)
			)
			(layer "F.Fab")
		)
		(fp_line
			(start -0.12065 0.3048)
			(end -0.67945 0.3048)
			(stroke
				(width 0.1)
				(type default)
			)
			(layer "F.Fab")
		)
		(fp_line
			(start -0.12065 0.2794)
			(end -0.12065 0.3048)
			(stroke
				(width 0.1)
				(type default)
			)
			(layer "F.Fab")
		)
		(fp_line
			(start -0.12065 -0.2794)
			(end 0.12065 -0.2794)
			(stroke
				(width 0.1)
				(type default)
			)
			(layer "F.Fab")
		)
		(fp_line
			(start -0.12065 -0.305054)
			(end -0.12065 -0.2794)
			(stroke
				(width 0.1)
				(type default)
			)
			(layer "F.Fab")
		)
		(fp_line
			(start -0.67945 0.3048)
			(end -0.67945 -0.305054)
			(stroke
				(width 0.1)
				(type default)
			)
			(layer "F.Fab")
		)
		(fp_line
			(start -0.67945 -0.305054)
			(end -0.12065 -0.305054)
			(stroke
				(width 0.1)
				(type default)
			)
			(layer "F.Fab")
		)
		(pad "1" smd circle
			(at -0.40005 0 180)
			(size 0 0)
			(layers "F.Cu" "F.Mask" "F.Paste")
			(net "PWRGD_P52V_HS1_PG")
		)
		(pad "2" smd circle
			(at 0.40005 0 180)
			(size 0 0)
			(layers "F.Cu" "F.Mask" "F.Paste")
			(net "GND_FIELD_SIGNAL")
		)
	)
)
